FILE_TYPE = CONNECTIVITY;
{Allegro Design Entry HDL 17.2-2016 S081 (4005846) 1/11/2022}
"PAGE_NUMBER" = 282;
0"NC";
1"P3V3_AUX\g";
2"P3V3_AUX\g";
3"PVNN_TERM_CPU1\g";
4"PVCCD_HV_CPU1\g";
5"P3V3_AUX\g";
6"P3V3_AUX\g";
7"GND\g";
8"GND\g";
9"GND\g";
10"GND\g";
11"GND\g";
12"GND\g";
13"GND\g";
14"GND\g";
15"GND\g";
16"GND\g";
17"GND\g";
18"GND\g";
19"GND\g";
20"GND\g";
21"GND\g";
22"GND\g";
23"GND\g";
24"GND\g";
25"GND\g";
26"GND\g";
27"GND\g";
28"NC_PVCCD_HV_CPU1_APWM2";
29"SMB_CLK_PVCCD_HV_CPU1";
30"SVID_DIO_PVCCD_HV_CPU1_R";
31"SVID_ALERT_PVCCD_HV_CPU1_R";
32"NC_PVCCD_HV_CPU1_BVR_RDY";
33"SVID_CLK_PVCCD_HV_CPU1_R";
34"NC_PVCCD_HV_CPU1_SMB_ALERT";
35"PVCCD_HV_CPU1_EN_R";
36"VSENSE_PVCCD_HV_CPU1_DN";
37"SMB_DIO_PVCCD_HV_CPU1";
38"SH_PVCCD_HV_CPU1_R";
39"PWRGD_PVCCD_HV_CPU1_R";
40"PVCCD_HV_CPU1_ISENSE_P";
41"PVCCD_HV_CPU1_ISENSE_N";
42"PVCCD_HV_CPU1_PIN_ALT";
43"PVCCD_HV_CPU1_FAULT";
44"PVCCD_HV_CPU1_ADDR";
45"NC_PVCCD_HV_CPU1_ACSP8";
46"NC_PVCCD_HV_CPU1_APWM8";
47"PVCCD_HV_CPU1_ATSEN";
48"NC_PVCCD_HV_CPU1_ACSP6";
49"NC_PVCCD_HV_CPU1_APWM6";
50"NC_PVCCD_HV_CPU1_ACSP5";
51"NC_PVCCD_HV_CPU1_APWM5";
52"PVCCD_HV_CPU1_APWM1";
53"NC_PVCCD_HV_CPU1_ACSP7";
54"PVCCD_HV_CPU1_ISYS_R";
55"PVCCD_HV_CPU1_VREF";
56"NC_PVCCD_HV_CPU1_APWM7";
57"NC_PVCCD_HV_CPU1_APWM3";
58"NC_PVCCD_HV_CPU1_APWM4";
59"NC_PVCCD_HV_CPU1_ACSP4";
60"NC_PVCCD_HV_CPU1_ACSP3";
61"IRQ_PVCCD_CPU1_VRHOT_LVC3_R_N";
62"NC_PVCCD_HV_CPU1_ACSP2";
63"PVCCD_HV_CPU1_VCC";
64"PVCCD_HV_CPU1_ACSP1";
65"SMB_VR_3V3AUX_SDA_R";
66"PVCCD_HV_CPU1_VREF";
67"P12V_AUX_CPU1_DIMM_ISEN_P";
68"SVID_ALERT1_CPU1_R_N";
69"PVCCD_HV_CPU1_NVDIMM_ISENSE";
70"IRQ_PVCCD_CPU1_VRHOT_LVC3_N";
71"PWRGD_PVCCD_HV_CPU1";
72"FM_PVCCD_HV_CPU1_EN";
73"SVID_CLK1_CPU1_R";
74"SVID_DIO1_CPU1_R";
75"SMB_VR_3V3AUX_SCL_R";
76"VSENSE_PVCCD_HV_CPU1_DP";
77"SH_PVCCD_HV_CPU1";
78"P12V_AUX_CPU1_DIMM_ISEN_N";
%"Q_RES"
"1","(-5400,0)","0","pure_quanta","I10";
;
PART_NUMBER"CS04992FB07"
MATERIAL"CHIP"
VALUE"49.9"
TOLERANCE"1%"
PACK_TYPE"0402LF"
WATTAGE"1/16W"
LOCATION"PR1410"
CDS_LIB"pure_quanta"
$SEC"1"
CDS_SEC"1";
"B"
$PN"2"41;
"A"
$PN"1"78;
%"Q_RES"
"2","(-5000,-200)","2","pure_quanta","I11";
;
PART_NUMBER"CS21002FB06"
TOLERANCE"1%"
WATTAGE"1/16W"
MATERIAL"EMPTY"
VALUE"1K"
PACK_TYPE"0402LF"
LOCATION"PR214"
CDS_LIB"pure_quanta"
LOCATION"PR214"
$SEC"1"
CDS_SEC"1";
"A"
$PN"1"40;
"B"
$PN"2"8;
%"UNIVERSAL_GND"
"1","(-4875,-500)","0","logical_power","I12";
;
HDL_POWER"GND"
CDS_LIB"logical_power";
"A"8;
%"Q_CAP"
"1","(-4875,-200)","0","pure_quanta","I13";
;
PART_NUMBER"CH4104K1B00"
VOLTAGE"25V"
VALUE"0.1UF"
TOLERANCE"10%"
MATERIAL"X7R"
PACK_TYPE"0402"
LOCATION"PC386"
CDS_LIB"pure_quanta"
LOCATION"PC386"
$SEC"1"
CDS_SEC"1";
"B"
$PN"2"8;
"A"
$PN"1"40;
%"Q_RES"
"1","(-5975,2925)","0","pure_quanta","I15";
;
PART_NUMBER"CS11002FB07"
WATTAGE"1/16W"
MATERIAL"CHIP"
TOLERANCE"1%"
VALUE"100"
PACK_TYPE"0402LF"
LOCATION"PR558"
CDS_LIB"pure_quanta"
$SEC"1"
CDS_SEC"1";
"B"
$PN"2"9;
"A"
$PN"1"36;
%"Q_SHORT"
"1","(-6025,3450)","0","pure_quanta","I16";
;
PART_NUMBER"SHORT6"
PACK_TYPE"SM"
MATERIAL"EMPTY"
LOCATION"PJ48"
CDS_LIB"pure_quanta"
NEEDS_NO_SIZE"TRUE"
LOCATION"PJ48"
$SEC"1"
CDS_SEC"1";
"1"
$PN"1"76;
"2"
$PN"2"77;
%"UNIVERSAL_GND"
"1","(-5450,2825)","0","logical_power","I17";
;
HDL_POWER"GND"
CDS_LIB"logical_power";
"A"9;
%"Q_RES"
"2","(-5075,1750)","0","pure_quanta","I18";
;
PART_NUMBER"CS21002FB06"
VALUE"1K"
WATTAGE"1/16W"
TOLERANCE"1%"
MATERIAL"CHIP"
PACK_TYPE"0402LF"
LOCATION"PR215"
CDS_LIB"pure_quanta"
LOCATION"PR215"
$SEC"1"
CDS_SEC"1";
"A"
$PN"1"2;
"B"
$PN"2"42;
%"VCC15"
"1","(-5075,2100)","0","logical_power","I19";
;
HDL_POWER"P3V3_AUX"
CDS_LIB"logical_power";
"A"2;
%"Q_RES"
"2","(-4750,1750)","0","pure_quanta","I20";
;
PART_NUMBER"CS21002FB06"
TOLERANCE"1%"
VALUE"1K"
MATERIAL"CHIP"
PACK_TYPE"0402LF"
WATTAGE"1/16W"
LOCATION"PR217"
CDS_LIB"pure_quanta"
LOCATION"PR217"
$SEC"1"
CDS_SEC"1";
"A"
$PN"1"2;
"B"
$PN"2"43;
%"Q_RES"
"1","(-4925,3450)","0","pure_quanta","I21";
;
PART_NUMBER"CS00002JB13"
TOLERANCE"5%"
PACK_TYPE"0402LF"
VALUE"0"
WATTAGE"1/16W"
MATERIAL"CHIP"
LOCATION"PR216"
CDS_LIB"pure_quanta"
LOCATION"PR216"
$SEC"1"
CDS_SEC"1";
"B"
$PN"2"38;
"A"
$PN"1"77;
%"Q_CAP"
"1","(-4475,3275)","0","pure_quanta","I22";
;
PART_NUMBER"TMP_QCH2336K1B12"
PACK_TYPE"0402"
MATERIAL"X7R"
TOLERANCE"10%"
VOLTAGE"50V"
VALUE"3300PF"
LOCATION"PC389"
CDS_LIB"pure_quanta"
LOCATION"PC389"
$SEC"1"
CDS_SEC"1";
"B"
$PN"2"36;
"A"
$PN"1"38;
%"UNIVERSAL_GND"
"1","(-7550,4825)","0","logical_power","I23";
;
HDL_POWER"GND"
CDS_LIB"logical_power";
"A"10;
%"Q_CAP"
"1","(-7550,5175)","0","pure_quanta","I24";
;
PART_NUMBER"CH6101MEB03"
VALUE"10UF"
VOLTAGE"6.3V"
TOLERANCE"20%"
MATERIAL"X6S"
PACK_TYPE"C0402"
LOCATION"C1336"
CDS_LIB"pure_quanta"
$SEC"1"
CDS_SEC"1";
"B"
$PN"2"10;
"A"
$PN"1"3;
%"VCC15"
"1","(-7550,5450)","0","logical_power","I25";
;
HDL_POWER"PVNN_TERM_CPU1"
CDS_LIB"logical_power";
"A"3;
%"Q_CAP"
"1","(-7325,5175)","0","pure_quanta","I28";
;
PART_NUMBER"CH4104K1B00"
VOLTAGE"25V"
TOLERANCE"10%"
MATERIAL"X7R"
VALUE"0.1UF"
PACK_TYPE"0402"
LOCATION"C1337"
CDS_LIB"pure_quanta"
$SEC"1"
CDS_SEC"1";
"B"
$PN"2"10;
"A"
$PN"1"3;
%"Q_RES"
"1","(-6800,5075)","0","pure_quanta","I29";
;
PART_NUMBER"CS11002FB07"
MATERIAL"CHIP"
TOLERANCE"1%"
VALUE"100"
PACK_TYPE"0402LF"
WATTAGE"1/16W"
LOCATION"R2593"
CDS_LIB"pure_quanta"
$SEC"1"
CDS_SEC"1";
"B"
$PN"2"74;
"A"
$PN"1"3;
%"Q_RES"
"1","(-6800,5175)","0","pure_quanta","I33";
;
PART_NUMBER"CS04992FB07"
VALUE"49.9"
TOLERANCE"1%"
MATERIAL"CHIP"
WATTAGE"1/16W"
PACK_TYPE"0402LF"
LOCATION"R1718"
CDS_LIB"pure_quanta"
$SEC"1"
CDS_SEC"1";
"B"
$PN"2"73;
"A"
$PN"1"3;
%"Q_RES"
"1","(-5950,3600)","0","pure_quanta","I36";
;
PART_NUMBER"CS11002FB07"
PACK_TYPE"0402LF"
WATTAGE"1/16W"
TOLERANCE"1%"
MATERIAL"CHIP"
VALUE"100"
LOCATION"PR559"
CDS_LIB"pure_quanta"
$SEC"1"
CDS_SEC"1";
"B"
$PN"2"4;
"A"
$PN"1"76;
%"VCC15"
"1","(-5450,3750)","0","logical_power","I37";
;
HDL_POWER"PVCCD_HV_CPU1"
CDS_LIB"logical_power";
"A"4;
%"Q_RES"
"1","(-5325,4150)","0","pure_quanta","I38";
;
PART_NUMBER"CS00002JB13"
VALUE"0"
MATERIAL"CHIP"
TOLERANCE"5%"
WATTAGE"1/16W"
PACK_TYPE"0402LF"
LOCATION"R2582"
CDS_LIB"pure_quanta"
SEC_TYPE"0402LF"
SEC"1";
"B"
$PN"2"37;
"A"
$PN"1"65;
%"Q_RES"
"1","(-5325,4300)","0","pure_quanta","I39";
;
PART_NUMBER"CS00002JB13"
TOLERANCE"5%"
MATERIAL"CHIP"
VALUE"0"
PACK_TYPE"0402LF"
WATTAGE"1/16W"
LOCATION"R4595"
CDS_LIB"pure_quanta"
LOCATION"R4595"
$SEC"1"
CDS_SEC"1";
"B"
$PN"2"29;
"A"
$PN"1"75;
%"UNIVERSAL_GND"
"1","(-6850,150)","0","logical_power","I4";
;
HDL_POWER"GND"
CDS_LIB"logical_power";
"A"7;
%"Q_RES"
"1","(-5325,4700)","0","pure_quanta","I40";
;
PART_NUMBER"CS00002JB13"
MATERIAL"CHIP"
VALUE"0"
WATTAGE"1/16W"
TOLERANCE"5%"
PACK_TYPE"0402LF"
LOCATION"R2580"
CDS_LIB"pure_quanta"
LOCATION"R2580"
$SEC"1"
CDS_SEC"1";
"B"
$PN"2"31;
"A"
$PN"1"68;
%"Q_RES"
"1","(-5325,4850)","0","pure_quanta","I41";
;
PART_NUMBER"CS00002JB13"
PACK_TYPE"0402LF"
TOLERANCE"5%"
VALUE"0"
WATTAGE"1/16W"
MATERIAL"CHIP"
LOCATION"R2579"
CDS_LIB"pure_quanta"
LOCATION"R2579"
$SEC"1"
CDS_SEC"1";
"B"
$PN"2"30;
"A"
$PN"1"74;
%"Q_RES"
"1","(-5325,5000)","0","pure_quanta","I42";
;
PART_NUMBER"CS11502FB07"
MATERIAL"CHIP"
WATTAGE"1/16W"
VALUE"150"
TOLERANCE"1%"
PACK_TYPE"0402LF"
LOCATION"R2578"
CDS_LIB"pure_quanta"
LOCATION"R2578"
$SEC"1"
CDS_SEC"1";
"B"
$PN"2"33;
"A"
$PN"1"73;
%"Q_RES"
"1","(-5325,5300)","0","pure_quanta","I43";
;
PART_NUMBER"CS00002JB13"
MATERIAL"CHIP"
WATTAGE"1/16W"
VALUE"0"
PACK_TYPE"0402LF"
TOLERANCE"5%"
LOCATION"R2577"
CDS_LIB"pure_quanta"
LOCATION"R2577"
$SEC"1"
CDS_SEC"1";
"B"
$PN"2"35;
"A"
$PN"1"72;
%"Q_RES"
"1","(-5325,5450)","0","pure_quanta","I44";
;
PART_NUMBER"CS00002JB13"
MATERIAL"CHIP"
TOLERANCE"5%"
VALUE"0"
PACK_TYPE"0402LF"
WATTAGE"1/16W"
LOCATION"R2576"
CDS_LIB"pure_quanta"
LOCATION"R2576"
$SEC"1"
CDS_SEC"1";
"B"
$PN"2"39;
"A"
$PN"1"71;
%"Q_CAP"
"2","(-4475,5600)","0","pure_quanta","I45";
;
PART_NUMBER"TMP_QCH21006JB10"
PACK_TYPE"0402"
TOLERANCE"5%"
VOLTAGE"50V"
MATERIAL"EMPTY"
VALUE"1000PF"
LOCATION"C2454"
CDS_LIB"pure_quanta"
LOCATION"C2454"
$SEC"1"
CDS_SEC"1";
"A"
$PN"1"39;
"B"
$PN"2"16;
%"Q_RES"
"1","(-5325,5600)","0","pure_quanta","I46";
;
PART_NUMBER"CS21002FB06"
MATERIAL"CHIP"
TOLERANCE"1%"
VALUE"1K"
PACK_TYPE"0402LF"
WATTAGE"1/16W"
LOCATION"R2575"
CDS_LIB"pure_quanta"
LOCATION"R2575"
$SEC"1"
CDS_SEC"1";
"B"
$PN"2"39;
"A"
$PN"1"5;
%"VCC15"
"1","(-5750,5700)","0","logical_power","I47";
;
HDL_POWER"P3V3_AUX"
CDS_LIB"logical_power";
"A"5;
%"Q_RES"
"2","(-4150,-200)","2","pure_quanta","I48";
;
PART_NUMBER"CS21002FB06"
VALUE"1K"
WATTAGE"1/16W"
MATERIAL"EMPTY"
TOLERANCE"1%"
PACK_TYPE"0402LF"
LOCATION"PR218"
CDS_LIB"pure_quanta"
LOCATION"PR218"
$SEC"1"
CDS_SEC"1";
"A"
$PN"1"41;
"B"
$PN"2"11;
%"UNIVERSAL_GND"
"1","(-4025,-500)","0","logical_power","I49";
;
HDL_POWER"GND"
CDS_LIB"logical_power";
"A"11;
%"Q_CAP"
"1","(-4025,-200)","0","pure_quanta","I50";
;
PART_NUMBER"CH4104K1B00"
MATERIAL"X7R"
TOLERANCE"10%"
VALUE"0.1UF"
VOLTAGE"25V"
PACK_TYPE"0402"
LOCATION"PC390"
CDS_LIB"pure_quanta"
LOCATION"PC390"
$SEC"1"
CDS_SEC"1";
"B"
$PN"2"11;
"A"
$PN"1"41;
%"Q_CAP"
"2","(-4125,50)","0","pure_quanta","I51";
;
PART_NUMBER"CH5103KEB01"
MATERIAL"X6S"
VOLTAGE"16V"
VALUE"1UF"
TOLERANCE"10%"
PACK_TYPE"C0402"
LOCATION"PC814"
CDS_LIB"pure_quanta"
$SEC"1"
CDS_SEC"1";
"A"
$PN"1"41;
"B"
$PN"2"40;
%"UNIVERSAL_GND"
"1","(-3725,-225)","0","logical_power","I52";
;
HDL_POWER"GND"
CDS_LIB"logical_power";
"A"12;
%"ISL69260IRAZT"
"1","(-2950,2700)","0","pure_quanta","I53";
;
PART_NUMBER"AL069260000"
VALUE"ISL69260IRAZ-T"
PART_TYPE"SMLF"
MATERIAL"IC"
LOCATION"PU18"
NEEDS_NO_SIZE"TRUE"
CDS_LMAN_SYM_OUTLINE"-550,2850,500,-2850"
CDS_LIB"pure_quanta"
$SEC"1"
CDS_SEC"1";
"CS0"
$PN"30"45;
"PWM0"
$PN"1"46;
"TEMP0"
$PN"35"47;
"ADDR_CFG"
$PN"34"44;
"TH_GND"
$PN"TH"12;
"CFP"
$PN"33"43;
"CS2"
$PN"28"48;
"PWM2"
$PN"3"49;
"CS3"
$PN"27"50;
"PWM3"
$PN"4"51;
"PWM7"
$PN"8"52;
"CS1"
$PN"29"53;
"RGND1"
$PN"31"14;
"VSEN1"
$PN"32"14;
"NPINALERT#||NPSYSCRIT# \B"
$PN"15"42;
"TEMP1||ISYS"
$PN"36"54;
"VINSEN||VSYS"
$PN"38"41;
"VMON||IINSEN||VSYS||ISYS"
$PN"37"40;
"VCCS"
$PN"40"55;
"PWM6"
$PN"7"28;
"PG0"
$PN"12"39;
"PWM1"
$PN"2"56;
"VSEN0"
$PN"21"38;
"PWM5"
$PN"6"57;
"PWM4"
$PN"5"58;
"PMSDA"
$PN"9"37;
"RGND0"
$PN"22"36;
"EN0"
$PN"13"35;
"NPMALERT# \B"
$PN"11"34;
"SVCLK"
$PN"17"33;
"PG1"
$PN"16"32;
"CS4"
$PN"26"59;
"CS5"
$PN"25"60;
"NVRHOT# \B"
$PN"14"61;
"NSVALERT# \B"
$PN"19"31;
"CS6"
$PN"24"62;
"SVDATA"
$PN"18"30;
"PMSCL"
$PN"10"29;
"EN1"
$PN"20"13;
"VCC"
$PN"39"63;
"CS7"
$PN"23"64;
%"UNIVERSAL_GND"
"1","(-3775,925)","0","logical_power","I54";
;
HDL_POWER"GND"
CDS_LIB"logical_power";
"A"13;
%"UNIVERSAL_GND"
"1","(-3825,1850)","0","logical_power","I55";
;
HDL_POWER"GND"
CDS_LIB"logical_power";
"A"14;
%"UNIVERSAL_GND"
"1","(-1325,-175)","0","logical_power","I56";
;
HDL_POWER"GND"
CDS_LIB"logical_power";
"A"15;
%"Q_CAP"
"1","(-1325,50)","0","pure_quanta","I57";
;
PART_NUMBER"TMP_QCH14706KB18"
MATERIAL"X7R"
TOLERANCE"10%"
VALUE"470PF"
VOLTAGE"50V"
PACK_TYPE"0402"
LOCATION"PC393"
CDS_LIB"pure_quanta"
LOCATION"PC393"
$SEC"1"
CDS_SEC"1";
"B"
$PN"2"15;
"A"
$PN"1"47;
%"Q_RES"
"1","(-800,950)","0","pure_quanta","I58";
;
PART_NUMBER"CS00002JB13"
PACK_TYPE"0402LF"
WATTAGE"1/16W"
VALUE"0"
TOLERANCE"5%"
MATERIAL"CHIP"
LOCATION"R2557"
CDS_LIB"pure_quanta"
SEC_TYPE"0402LF"
SEC"1";
"B"
$PN"2"70;
"A"
$PN"1"61;
%"Q_RES"
"1","(-800,1200)","0","pure_quanta","I59";
;
PART_NUMBER"CS00002JB13"
MATERIAL"CHIP"
VALUE"0"
TOLERANCE"5%"
LOCATION"PR4257"
CDS_LIB"pure_quanta"
PACK_TYPE"0402LF"
WATTAGE"1/16W"
$SEC"1"
CDS_SEC"1";
"B"
$PN"2"21;
"A"
$PN"1"45;
%"Q_RES"
"1","(-475,550)","0","pure_quanta","I60";
;
PART_NUMBER"CS00002JB13"
PACK_TYPE"0402LF"
WATTAGE"1/16W"
MATERIAL"CHIP"
TOLERANCE"5%"
VALUE"0"
LOCATION"PR1315"
CDS_LIB"pure_quanta"
$SEC"1"
CDS_SEC"1";
"B"
$PN"2"20;
"A"
$PN"1"54;
%"Q_RES"
"1","(-475,800)","0","pure_quanta","I61";
;
PART_NUMBER"CS00002JB13"
PACK_TYPE"0402LF"
WATTAGE"1/16W"
MATERIAL"EMPTY"
VALUE"0"
TOLERANCE"5%"
LOCATION"PR410"
CDS_LIB"pure_quanta"
$SEC"1"
CDS_SEC"1";
"B"
$PN"2"69;
"A"
$PN"1"54;
%"Q_RES"
"1","(-800,2100)","0","pure_quanta","I62";
;
PART_NUMBER"CS00002JB13"
MATERIAL"CHIP"
WATTAGE"1/16W"
PACK_TYPE"0402LF"
TOLERANCE"5%"
VALUE"0"
LOCATION"PR4255"
CDS_LIB"pure_quanta"
$SEC"1"
CDS_SEC"1";
"B"
$PN"2"23;
"A"
$PN"1"48;
%"Q_RES"
"1","(-800,1650)","0","pure_quanta","I63";
;
PART_NUMBER"CS00002JB13"
MATERIAL"CHIP"
WATTAGE"1/16W"
PACK_TYPE"0402LF"
TOLERANCE"5%"
VALUE"0"
LOCATION"PR4256"
CDS_LIB"pure_quanta"
$SEC"1"
CDS_SEC"1";
"B"
$PN"2"22;
"A"
$PN"1"53;
%"Q_RES"
"1","(-800,3450)","0","pure_quanta","I64";
;
PART_NUMBER"CS00002JB13"
MATERIAL"CHIP"
WATTAGE"1/16W"
PACK_TYPE"0402LF"
TOLERANCE"5%"
VALUE"0"
LOCATION"PR4252"
CDS_LIB"pure_quanta"
$SEC"1"
CDS_SEC"1";
"B"
$PN"2"26;
"A"
$PN"1"60;
%"Q_RES"
"1","(-800,3000)","0","pure_quanta","I65";
;
PART_NUMBER"CS00002JB13"
WATTAGE"1/16W"
PACK_TYPE"0402LF"
TOLERANCE"5%"
VALUE"0"
MATERIAL"CHIP"
LOCATION"PR4253"
CDS_LIB"pure_quanta"
$SEC"1"
CDS_SEC"1";
"B"
$PN"2"25;
"A"
$PN"1"59;
%"Q_RES"
"1","(-800,2550)","0","pure_quanta","I66";
;
PART_NUMBER"CS00002JB13"
WATTAGE"1/16W"
MATERIAL"CHIP"
TOLERANCE"5%"
VALUE"0"
PACK_TYPE"0402LF"
LOCATION"PR4254"
CDS_LIB"pure_quanta"
$SEC"1"
CDS_SEC"1";
"B"
$PN"2"24;
"A"
$PN"1"50;
%"UNIVERSAL_GND"
"1","(-3775,5600)","1","logical_power","I67";
;
HDL_POWER"GND"
CDS_LIB"logical_power";
"A"16;
%"Q_CAP"
"1","(-1700,4775)","0","pure_quanta","I68";
;
PART_NUMBER"CH6101MEB03"
PACK_TYPE"C0402"
VALUE"10UF"
TOLERANCE"20%"
MATERIAL"X6S"
VOLTAGE"6.3V"
LOCATION"PC392"
CDS_LIB"pure_quanta"
LOCATION"PC392"
$SEC"1"
CDS_SEC"1";
"B"
$PN"2"17;
"A"
$PN"1"55;
%"Q_CAP"
"1","(-1700,5250)","0","pure_quanta","I69";
;
PART_NUMBER"CH4106K1B01"
VOLTAGE"50V"
VALUE"100NF"
PACK_TYPE"C0402"
MATERIAL"EMPTY"
TOLERANCE"10%"
LOCATION"PC391"
CDS_LIB"pure_quanta"
LOCATION"PC391"
$SEC"1"
CDS_SEC"1";
"B"
$PN"2"18;
"A"
$PN"1"63;
%"Q_RES"
"1","(-800,3900)","0","pure_quanta","I70";
;
PART_NUMBER"CS00002JB13"
MATERIAL"CHIP"
VALUE"0"
TOLERANCE"5%"
WATTAGE"1/16W"
PACK_TYPE"0402LF"
LOCATION"PR4251"
CDS_LIB"pure_quanta"
$SEC"1"
CDS_SEC"1";
"B"
$PN"2"27;
"A"
$PN"1"62;
%"UNIVERSAL_GND"
"1","(-850,4575)","3","logical_power","I73";
;
HDL_POWER"GND"
CDS_LIB"logical_power";
"A"17;
%"Q_CAP"
"1","(-1300,4775)","0","pure_quanta","I74";
;
PART_NUMBER"CH5103KEB01"
MATERIAL"X6S"
VALUE"1UF"
VOLTAGE"16V"
PACK_TYPE"C0402"
TOLERANCE"10%"
LOCATION"PC1289"
CDS_LIB"pure_quanta"
$SEC"1"
CDS_SEC"1";
"B"
$PN"2"17;
"A"
$PN"1"55;
%"UNIVERSAL_GND"
"1","(-850,5050)","3","logical_power","I75";
;
HDL_POWER"GND"
CDS_LIB"logical_power";
"A"18;
%"Q_CAP"
"1","(-1300,5250)","0","pure_quanta","I77";
;
PART_NUMBER"CH5103KEB01"
MATERIAL"X6S"
TOLERANCE"10%"
PACK_TYPE"C0402"
VALUE"1UF"
VOLTAGE"16V"
LOCATION"PC394"
CDS_LIB"pure_quanta"
LOCATION"PC394"
$SEC"1"
CDS_SEC"1";
"B"
$PN"2"18;
"A"
$PN"1"63;
%"Q_RES"
"1","(-975,5450)","0","pure_quanta","I78";
;
PART_NUMBER"CS-1002FB04"
VALUE"1"
TOLERANCE"1%"
WATTAGE"1/16W"
PACK_TYPE"0402LF"
MATERIAL"CHIP"
LOCATION"PR220"
CDS_LIB"pure_quanta"
LOCATION"PR220"
$SEC"1"
CDS_SEC"1";
"B"
$PN"2"6;
"A"
$PN"1"63;
%"VCC15"
"1","(-500,5575)","0","logical_power","I79";
;
HDL_POWER"P3V3_AUX"
CDS_LIB"logical_power";
"A"6;
%"Q_RES"
"1","(-6200,350)","0","pure_quanta","I8";
;
PART_NUMBER"CS32802FB05"
TOLERANCE"1%"
PACK_TYPE"0402LF"
VALUE"28K"
WATTAGE"1/16W"
MATERIAL"EMPTY"
LOCATION"PR202"
CDS_LIB"pure_quanta"
LOCATION"PR202"
$SEC"1"
CDS_SEC"1";
"B"
$PN"2"44;
"A"
$PN"1"66;
%"UNIVERSAL_GND"
"1","(-175,-200)","0","logical_power","I80";
;
HDL_POWER"GND"
CDS_LIB"logical_power";
"A"19;
%"Q_RES"
"2","(-175,50)","0","pure_quanta","I81";
;
PART_NUMBER"CS31002FB08"
PACK_TYPE"0402LF"
WATTAGE"1/16W"
TOLERANCE"1%"
MATERIAL"EMPTY"
VALUE"10K"
LOCATION"PR705"
CDS_LIB"pure_quanta"
$SEC"1"
CDS_SEC"1";
"A"
$PN"1"47;
"B"
$PN"2"19;
%"UNIVERSAL_GND"
"1","(250,425)","0","logical_power","I82";
;
HDL_POWER"GND"
CDS_LIB"logical_power";
"A"20;
%"UNIVERSAL_GND"
"1","(-175,1125)","0","logical_power","I84";
;
HDL_POWER"GND"
CDS_LIB"logical_power";
"A"21;
%"Q_RES"
"2","(100,1225)","0","pure_quanta","I85";
;
PART_NUMBER"CS21002FB06"
VALUE"1K"
WATTAGE"1/16W"
MATERIAL"CHIP"
TOLERANCE"1%"
PACK_TYPE"0402LF"
LOCATION"R223"
CDS_LIB"pure_quanta"
LOCATION"R223"
$SEC"1"
CDS_SEC"1";
"A"
$PN"1"1;
"B"
$PN"2"70;
%"VCC15"
"1","(100,1475)","0","logical_power","I86";
;
HDL_POWER"P3V3_AUX"
CDS_LIB"logical_power";
"A"1;
%"UNIVERSAL_GND"
"1","(-175,1575)","0","logical_power","I89";
;
HDL_POWER"GND"
CDS_LIB"logical_power";
"A"22;
%"Q_RES"
"1","(-5400,100)","0","pure_quanta","I9";
;
PART_NUMBER"CS04992FB07"
MATERIAL"CHIP"
VALUE"49.9"
TOLERANCE"1%"
LOCATION"PR1400"
CDS_LIB"pure_quanta"
WATTAGE"1/16W"
PACK_TYPE"0402LF"
$SEC"1"
CDS_SEC"1";
"B"
$PN"2"40;
"A"
$PN"1"67;
%"UNIVERSAL_GND"
"1","(-175,2025)","0","logical_power","I90";
;
HDL_POWER"GND"
CDS_LIB"logical_power";
"A"23;
%"UNIVERSAL_GND"
"1","(-175,2475)","0","logical_power","I91";
;
HDL_POWER"GND"
CDS_LIB"logical_power";
"A"24;
%"UNIVERSAL_GND"
"1","(-175,2925)","0","logical_power","I92";
;
HDL_POWER"GND"
CDS_LIB"logical_power";
"A"25;
%"UNIVERSAL_GND"
"1","(-175,3375)","0","logical_power","I93";
;
HDL_POWER"GND"
CDS_LIB"logical_power";
"A"26;
%"UNIVERSAL_GND"
"1","(-175,3825)","0","logical_power","I94";
;
HDL_POWER"GND"
CDS_LIB"logical_power";
"A"27;
%"Q_RES"
"1","(-6200,225)","0","pure_quanta","I95";
;
PART_NUMBER"CS32432FB03"
TOLERANCE"1%"
VALUE"24.3K"
WATTAGE"1/16W"
MATERIAL"CHIP"
LOCATION"PR203"
CDS_LIB"pure_quanta"
PACK_TYPE"0402LF"
$SEC"1"
CDS_SEC"1";
"B"
$PN"2"44;
"A"
$PN"1"7;
%"Q_CAP"
"1","(-2050,5250)","0","pure_quanta","I96";
;
PART_NUMBER"CH4104K1B00"
TOLERANCE"10%"
VALUE"0.1UF"
VOLTAGE"25V"
PACK_TYPE"0402"
MATERIAL"EMPTY"
LOCATION"PC2368"
CDS_LIB"pure_quanta"
$SEC"1"
CDS_SEC"1";
"B"
$PN"2"18;
"A"
$PN"1"63;
END.
